FILE_TYPE = MACRO_DRAWING;
SET COLOR_WIRE YELLOW;
SET COLOR_PROP MONO;
SET COLOR_DOT WHITE;
SET COLOR_ARC YELLOW;
SET COLOR_BODY GREEN;
SET COLOR_NOTE MONO;
SET PROP_DISPLAY VALUE;
SET PAGE_NUMBER P3;
FORCEADD INTEL_CORP_BPAGE..3
(4275 -200);
FORCEPROP 0 LAST CDS_CON_LAST_MODIFIED Fri Jun 16 17:47:55 2017
J 0
(2350 150);
PAINT MONO (2350 150);
DISPLAY INVISIBLE (2350 150);
FORCEPROP 2 LAST CUSTOM_TXT_CDS <XR_PAGE_TITLE>
J 0
(-3615 5050);
DISPLAY 0.638298 (-3615 5050);
PAINT PINK (-3615 5050);
DISPLAY INVISIBLE (-3615 5050);
FORCEPROP 2 LAST CUSTOM_TXT_CDS <CON_TC_SNM11>
J 0
(-2775 3325);
PAINT ORANGE (-2775 3325);
FORCEPROP 2 LAST CUSTOM_TXT_CDS <CON_TC_SNO4>
J 2
(-2875 4025);
PAINT ORANGE (-2875 4025);
FORCEPROP 2 LAST CUSTOM_TXT_CDS <CON_TC_SNM5>
J 0
(-2775 3925);
PAINT ORANGE (-2775 3925);
FORCEPROP 2 LAST CUSTOM_TXT_CDS <CON_TC_SNM92>
J 0
(2225 3225);
PAINT ORANGE (2225 3225);
FORCEPROP 2 LAST CUSTOM_TXT_CDS <CON_TC_SNM35>
J 0
(-2775 925);
PAINT ORANGE (-2775 925);
FORCEPROP 2 LAST CUSTOM_TXT_CDS <CON_TC_SNM2>
J 0
(-2775 4225);
PAINT ORANGE (-2775 4225);
FORCEPROP 2 LAST CUSTOM_TXT_CDS <CON_TC_SNM56>
J 0
(-275 2825);
PAINT ORANGE (-275 2825);
FORCEPROP 2 LAST CUSTOM_TXT_CDS <CON_TC_SNM109>
J 0
(2225 1525);
PAINT ORANGE (2225 1525);
FORCEPROP 2 LAST CUSTOM_TXT_CDS <CON_TC_SNO19>
J 2
(-2875 2525);
PAINT ORANGE (-2875 2525);
FORCEPROP 2 LAST CUSTOM_TXT_CDS <CON_TC_SNM49>
J 0
(-275 3525);
PAINT ORANGE (-275 3525);
FORCEPROP 2 LAST CUSTOM_TXT_CDS <CON_TC_SNM105>
J 0
(2225 1925);
PAINT ORANGE (2225 1925);
FORCEPROP 2 LAST CUSTOM_TXT_CDS <CON_TC_SNM63>
J 0
(-275 2125);
PAINT ORANGE (-275 2125);
FORCEPROP 2 LAST CUSTOM_TXT_CDS <CON_TC_SNM50>
J 0
(-275 3425);
PAINT ORANGE (-275 3425);
FORCEPROP 2 LAST CUSTOM_TXT_CDS <CON_TC_SNM108>
J 0
(2225 1625);
PAINT ORANGE (2225 1625);
FORCEPROP 2 LAST CUSTOM_TXT_CDS <CON_TC_SNM3>
J 0
(-2775 4125);
PAINT ORANGE (-2775 4125);
FORCEPROP 2 LAST CUSTOM_TXT_CDS <CON_TC_SNM44>
J 0
(-275 4025);
PAINT ORANGE (-275 4025);
FORCEPROP 2 LAST CUSTOM_TXT_CDS <CON_TC_SNM4>
J 0
(-2775 4025);
PAINT ORANGE (-2775 4025);
FORCEPROP 2 LAST CUSTOM_TXT_CDS <CON_TC_SNO3>
J 2
(-2875 4125);
PAINT ORANGE (-2875 4125);
FORCEPROP 2 LAST CUSTOM_TXT_CDS <CON_TC_SNM104>
J 0
(2225 2025);
PAINT ORANGE (2225 2025);
FORCEPROP 2 LAST CUSTOM_TXT_CDS <CON_TC_SNM6>
J 0
(-2775 3825);
PAINT ORANGE (-2775 3825);
FORCEPROP 2 LAST CUSTOM_TXT_CDS <CON_TC_SNM48>
J 0
(-275 3625);
PAINT ORANGE (-275 3625);
FORCEPROP 2 LAST CUSTOM_TXT_CDS <CON_TC_SNO2>
J 2
(-2875 4225);
PAINT ORANGE (-2875 4225);
FORCEPROP 2 LAST CUSTOM_TXT_CDS <CON_LAST_MODIFIED>
J 0
(275 -100);
PAINT ORANGE (275 -100);
FORCEPROP 2 LAST CUSTOM_TXT_CDS <CON_TC_SNM15>
J 0
(-2775 2925);
PAINT ORANGE (-2775 2925);
FORCEPROP 2 LAST CUSTOM_TXT_CDS <CON_TC_SNO1>
J 2
(-2875 4325);
PAINT ORANGE (-2875 4325);
FORCEPROP 2 LAST CUSTOM_TXT_CDS <CON_TC_SNM10>
J 0
(-2775 3425);
PAINT ORANGE (-2775 3425);
FORCEPROP 2 LAST CUSTOM_TXT_CDS <CON_TC_SNM75>
J 0
(-275 925);
PAINT ORANGE (-275 925);
FORCEPROP 2 LAST CUSTOM_TXT_CDS <CURRENT_DESIGN_SHEET> OF <TOTAL_DESIGN_SHEETS>
J 0
(3775 -175);
PAINT ORANGE (3775 -175);
FORCEPROP 2 LAST CUSTOM_TXT_CDS <CON_TC_SNM116>
J 0
(2225 825);
PAINT ORANGE (2225 825);
FORCEPROP 2 LAST CUSTOM_TXT_CDS <CON_TC_SNM115>
J 0
(2225 925);
PAINT ORANGE (2225 925);
FORCEPROP 2 LAST CUSTOM_TXT_CDS <CON_TC_SNM110>
J 0
(2225 1425);
PAINT ORANGE (2225 1425);
FORCEPROP 2 LAST CUSTOM_TXT_CDS <CON_TC_SNM107>
J 0
(2225 1725);
PAINT ORANGE (2225 1725);
FORCEPROP 2 LAST CUSTOM_TXT_CDS <CON_TC_SNM106>
J 0
(2225 1825);
PAINT ORANGE (2225 1825);
FORCEPROP 2 LAST CUSTOM_TXT_CDS <CON_TC_SNO104>
J 2
(2125 2025);
PAINT ORANGE (2125 2025);
FORCEPROP 2 LAST CUSTOM_TXT_CDS <CON_TC_SNO103>
J 2
(2125 2125);
PAINT ORANGE (2125 2125);
FORCEPROP 2 LAST CUSTOM_TXT_CDS <CON_TC_SNM55>
J 0
(-275 2925);
PAINT ORANGE (-275 2925);
FORCEPROP 2 LAST CUSTOM_TXT_CDS <CON_TC_SNM54>
J 0
(-275 3025);
PAINT ORANGE (-275 3025);
FORCEPROP 2 LAST CUSTOM_TXT_CDS <CON_TC_SNM53>
J 0
(-275 3125);
PAINT ORANGE (-275 3125);
FORCEPROP 2 LAST CUSTOM_TXT_CDS <CON_TC_SNM52>
J 0
(-275 3225);
PAINT ORANGE (-275 3225);
FORCEPROP 2 LAST CUSTOM_TXT_CDS <CON_TC_SNO50>
J 2
(-375 3425);
PAINT ORANGE (-375 3425);
FORCEPROP 2 LAST CUSTOM_TXT_CDS <CON_TC_SNO49>
J 2
(-375 3525);
PAINT ORANGE (-375 3525);
FORCEPROP 2 LAST CUSTOM_TXT_CDS <CON_TC_SNO48>
J 2
(-375 3625);
PAINT ORANGE (-375 3625);
FORCEPROP 2 LAST CUSTOM_TXT_CDS <CON_TC_SNO47>
J 2
(-375 3725);
PAINT ORANGE (-375 3725);
FORCEPROP 2 LAST CUSTOM_TXT_CDS <CON_TC_SNO46>
J 2
(-375 3825);
PAINT ORANGE (-375 3825);
FORCEPROP 2 LAST CUSTOM_TXT_CDS <CON_TC_SNO45>
J 2
(-375 3925);
PAINT ORANGE (-375 3925);
FORCEPROP 2 LAST CUSTOM_TXT_CDS <CON_TC_SNO44>
J 2
(-375 4025);
PAINT ORANGE (-375 4025);
FORCEPROP 2 LAST CUSTOM_TXT_CDS <CON_TC_SNM43>
J 0
(-275 4125);
PAINT ORANGE (-275 4125);
FORCEPROP 2 LAST CUSTOM_TXT_CDS <CON_TC_SNM42>
J 0
(-275 4225);
PAINT ORANGE (-275 4225);
FORCEPROP 2 LAST CUSTOM_TXT_CDS <CON_TC_SNM41>
J 0
(-275 4325);
PAINT ORANGE (-275 4325);
FORCEPROP 2 LAST CUSTOM_TXT_CDS <CON_TC_SNM76>
J 0
(-275 825);
PAINT ORANGE (-275 825);
FORCEPROP 2 LAST CUSTOM_TXT_CDS <CON_TC_SNM77>
J 0
(-275 725);
PAINT ORANGE (-275 725);
FORCEPROP 2 LAST CUSTOM_TXT_CDS <CON_TC_SNM79>
J 0
(-275 525);
PAINT ORANGE (-275 525);
FORCEPROP 2 LAST CUSTOM_TXT_CDS <CON_TC_SNM80>
J 0
(-275 425);
PAINT ORANGE (-275 425);
FORCEPROP 2 LAST CUSTOM_TXT_CDS <CON_TC_SNO115>
J 2
(2125 925);
PAINT ORANGE (2125 925);
FORCEPROP 2 LAST CUSTOM_TXT_CDS <CON_TC_SNM113>
J 0
(2225 1125);
PAINT ORANGE (2225 1125);
FORCEPROP 2 LAST CUSTOM_TXT_CDS <CON_TC_SNM112>
J 0
(2225 1225);
PAINT ORANGE (2225 1225);
FORCEPROP 2 LAST CUSTOM_TXT_CDS <CON_TC_SNM111>
J 0
(2225 1325);
PAINT ORANGE (2225 1325);
FORCEPROP 2 LAST CUSTOM_TXT_CDS <CON_TC_SNO6>
J 2
(-2875 3825);
PAINT ORANGE (-2875 3825);
FORCEPROP 2 LAST CUSTOM_TXT_CDS <CON_TC_SNO7>
J 2
(-2875 3725);
PAINT ORANGE (-2875 3725);
FORCEPROP 2 LAST CUSTOM_TXT_CDS <CON_TC_SNM8>
J 0
(-2775 3625);
PAINT ORANGE (-2775 3625);
FORCEPROP 2 LAST CUSTOM_TXT_CDS <CON_TC_SNM1>
J 0
(-2775 4325);
PAINT ORANGE (-2775 4325);
FORCEPROP 2 LAST CUSTOM_TXT_CDS <CON_TC_SNM19>
J 0
(-2775 2525);
PAINT ORANGE (-2775 2525);
FORCEPROP 2 LAST CUSTOM_TXT_CDS <CON_TC_SNM61>
J 0
(-275 2325);
PAINT ORANGE (-275 2325);
FORCEPROP 2 LAST CUSTOM_TXT_CDS <CON_TC_SNO38>
J 2
(-2875 625);
PAINT ORANGE (-2875 625);
FORCEPROP 2 LAST CUSTOM_TXT_CDS <CON_TC_SNM32>
J 0
(-2775 1225);
PAINT ORANGE (-2775 1225);
FORCEPROP 2 LAST CUSTOM_TXT_CDS <CON_TC_SNM27>
J 0
(-2775 1725);
PAINT ORANGE (-2775 1725);
FORCEPROP 2 LAST CUSTOM_TXT_CDS <CON_TC_SNM21>
J 0
(-2775 2325);
PAINT ORANGE (-2775 2325);
FORCEPROP 2 LAST CUSTOM_TXT_CDS <CON_TC_SNM17>
J 0
(-2775 2725);
PAINT ORANGE (-2775 2725);
FORCEPROP 2 LAST CUSTOM_TXT_CDS <CON_TC_SNO37>
J 2
(-2875 725);
PAINT ORANGE (-2875 725);
FORCEPROP 2 LAST CUSTOM_TXT_CDS <CON_TC_SNO120>
J 2
(2125 425);
PAINT ORANGE (2125 425);
FORCEPROP 2 LAST CUSTOM_TXT_CDS <CON_TC_SNO119>
J 2
(2125 525);
PAINT ORANGE (2125 525);
FORCEPROP 2 LAST CUSTOM_TXT_CDS <CON_TC_SNO118>
J 2
(2125 625);
PAINT ORANGE (2125 625);
FORCEPROP 2 LAST CUSTOM_TXT_CDS <CON_TC_SNO117>
J 2
(2125 725);
PAINT ORANGE (2125 725);
FORCEPROP 2 LAST CUSTOM_TXT_CDS <CON_TC_SNO116>
J 2
(2125 825);
PAINT ORANGE (2125 825);
FORCEPROP 2 LAST CUSTOM_TXT_CDS <CON_TC_SNO114>
J 2
(2125 1025);
PAINT ORANGE (2125 1025);
FORCEPROP 2 LAST CUSTOM_TXT_CDS <CON_TC_SNO113>
J 2
(2125 1125);
PAINT ORANGE (2125 1125);
FORCEPROP 2 LAST CUSTOM_TXT_CDS <CON_TC_SNO112>
J 2
(2125 1225);
PAINT ORANGE (2125 1225);
FORCEPROP 2 LAST CUSTOM_TXT_CDS <CON_TC_SNO111>
J 2
(2125 1325);
PAINT ORANGE (2125 1325);
FORCEPROP 2 LAST CUSTOM_TXT_CDS <CON_TC_SNO110>
J 2
(2125 1425);
PAINT ORANGE (2125 1425);
FORCEPROP 2 LAST CUSTOM_TXT_CDS <CON_TC_SNO109>
J 2
(2125 1525);
PAINT ORANGE (2125 1525);
FORCEPROP 2 LAST CUSTOM_TXT_CDS <CON_TC_SNO108>
J 2
(2125 1625);
PAINT ORANGE (2125 1625);
FORCEPROP 2 LAST CUSTOM_TXT_CDS <CON_TC_SNO107>
J 2
(2125 1725);
PAINT ORANGE (2125 1725);
FORCEPROP 2 LAST CUSTOM_TXT_CDS <CON_TC_SNO106>
J 2
(2125 1825);
PAINT ORANGE (2125 1825);
FORCEPROP 2 LAST CUSTOM_TXT_CDS <CON_TC_SNO105>
J 2
(2125 1925);
PAINT ORANGE (2125 1925);
FORCEPROP 2 LAST CUSTOM_TXT_CDS <CON_TC_SNO102>
J 2
(2125 2225);
PAINT ORANGE (2125 2225);
FORCEPROP 2 LAST CUSTOM_TXT_CDS <CON_TC_SNO101>
J 2
(2125 2325);
PAINT ORANGE (2125 2325);
FORCEPROP 2 LAST CUSTOM_TXT_CDS <CON_TC_SNO100>
J 2
(2125 2425);
PAINT ORANGE (2125 2425);
FORCEPROP 2 LAST CUSTOM_TXT_CDS <CON_TC_SNO99>
J 2
(2125 2525);
PAINT ORANGE (2125 2525);
FORCEPROP 2 LAST CUSTOM_TXT_CDS <CON_TC_SNO98>
J 2
(2125 2625);
PAINT ORANGE (2125 2625);
FORCEPROP 2 LAST CUSTOM_TXT_CDS <CON_TC_SNO97>
J 2
(2125 2725);
PAINT ORANGE (2125 2725);
FORCEPROP 2 LAST CUSTOM_TXT_CDS <CON_TC_SNO96>
J 2
(2125 2825);
PAINT ORANGE (2125 2825);
FORCEPROP 2 LAST CUSTOM_TXT_CDS <CON_TC_SNO95>
J 2
(2125 2925);
PAINT ORANGE (2125 2925);
FORCEPROP 2 LAST CUSTOM_TXT_CDS <CON_TC_SNO94>
J 2
(2125 3025);
PAINT ORANGE (2125 3025);
FORCEPROP 2 LAST CUSTOM_TXT_CDS <CON_TC_SNO93>
J 2
(2125 3125);
PAINT ORANGE (2125 3125);
FORCEPROP 2 LAST CUSTOM_TXT_CDS <CON_TC_SNO92>
J 2
(2125 3225);
PAINT ORANGE (2125 3225);
FORCEPROP 2 LAST CUSTOM_TXT_CDS <CON_TC_SNO91>
J 2
(2125 3325);
PAINT ORANGE (2125 3325);
FORCEPROP 2 LAST CUSTOM_TXT_CDS <CON_TC_SNO90>
J 2
(2125 3425);
PAINT ORANGE (2125 3425);
FORCEPROP 2 LAST CUSTOM_TXT_CDS <CON_TC_SNO89>
J 2
(2125 3525);
PAINT ORANGE (2125 3525);
FORCEPROP 2 LAST CUSTOM_TXT_CDS <CON_TC_SNO88>
J 2
(2125 3625);
PAINT ORANGE (2125 3625);
FORCEPROP 2 LAST CUSTOM_TXT_CDS <CON_TC_SNO87>
J 2
(2125 3725);
PAINT ORANGE (2125 3725);
FORCEPROP 2 LAST CUSTOM_TXT_CDS <CON_TC_SNO86>
J 2
(2125 3825);
PAINT ORANGE (2125 3825);
FORCEPROP 2 LAST CUSTOM_TXT_CDS <CON_TC_SNO85>
J 2
(2125 3925);
PAINT ORANGE (2125 3925);
FORCEPROP 2 LAST CUSTOM_TXT_CDS <CON_TC_SNO84>
J 2
(2125 4025);
PAINT ORANGE (2125 4025);
FORCEPROP 2 LAST CUSTOM_TXT_CDS <CON_TC_SNO83>
J 2
(2125 4125);
PAINT ORANGE (2125 4125);
FORCEPROP 2 LAST CUSTOM_TXT_CDS <CON_TC_SNO82>
J 2
(2125 4225);
PAINT ORANGE (2125 4225);
FORCEPROP 2 LAST CUSTOM_TXT_CDS <CON_TC_SNO81>
J 2
(2125 4325);
PAINT ORANGE (2125 4325);
FORCEPROP 2 LAST CUSTOM_TXT_CDS <CON_TC_SNO80>
J 2
(-375 425);
PAINT ORANGE (-375 425);
FORCEPROP 2 LAST CUSTOM_TXT_CDS <CON_TC_SNO79>
J 2
(-375 525);
PAINT ORANGE (-375 525);
FORCEPROP 2 LAST CUSTOM_TXT_CDS <CON_TC_SNO78>
J 2
(-375 625);
PAINT ORANGE (-375 625);
FORCEPROP 2 LAST CUSTOM_TXT_CDS <CON_TC_SNO77>
J 2
(-375 725);
PAINT ORANGE (-375 725);
FORCEPROP 2 LAST CUSTOM_TXT_CDS <CON_TC_SNO76>
J 2
(-375 825);
PAINT ORANGE (-375 825);
FORCEPROP 2 LAST CUSTOM_TXT_CDS <CON_TC_SNO75>
J 2
(-375 925);
PAINT ORANGE (-375 925);
FORCEPROP 2 LAST CUSTOM_TXT_CDS <CON_TC_SNO74>
J 2
(-375 1025);
PAINT ORANGE (-375 1025);
FORCEPROP 2 LAST CUSTOM_TXT_CDS <CON_TC_SNO73>
J 2
(-375 1125);
PAINT ORANGE (-375 1125);
FORCEPROP 2 LAST CUSTOM_TXT_CDS <CON_TC_SNO72>
J 2
(-375 1225);
PAINT ORANGE (-375 1225);
FORCEPROP 2 LAST CUSTOM_TXT_CDS <CON_TC_SNO71>
J 2
(-375 1325);
PAINT ORANGE (-375 1325);
FORCEPROP 2 LAST CUSTOM_TXT_CDS <CON_TC_SNO70>
J 2
(-375 1425);
PAINT ORANGE (-375 1425);
FORCEPROP 2 LAST CUSTOM_TXT_CDS <CON_TC_SNO69>
J 2
(-375 1525);
PAINT ORANGE (-375 1525);
FORCEPROP 2 LAST CUSTOM_TXT_CDS <CON_TC_SNO68>
J 2
(-375 1625);
PAINT ORANGE (-375 1625);
FORCEPROP 2 LAST CUSTOM_TXT_CDS <CON_TC_SNO67>
J 2
(-375 1725);
PAINT ORANGE (-375 1725);
FORCEPROP 2 LAST CUSTOM_TXT_CDS <CON_TC_SNO66>
J 2
(-375 1825);
PAINT ORANGE (-375 1825);
FORCEPROP 2 LAST CUSTOM_TXT_CDS <CON_TC_SNO65>
J 2
(-375 1925);
PAINT ORANGE (-375 1925);
FORCEPROP 2 LAST CUSTOM_TXT_CDS <CON_TC_SNO64>
J 2
(-375 2025);
PAINT ORANGE (-375 2025);
FORCEPROP 2 LAST CUSTOM_TXT_CDS <CON_TC_SNO63>
J 2
(-375 2125);
PAINT ORANGE (-375 2125);
FORCEPROP 2 LAST CUSTOM_TXT_CDS <CON_TC_SNO62>
J 2
(-375 2225);
PAINT ORANGE (-375 2225);
FORCEPROP 2 LAST CUSTOM_TXT_CDS <CON_TC_SNO61>
J 2
(-375 2325);
PAINT ORANGE (-375 2325);
FORCEPROP 2 LAST CUSTOM_TXT_CDS <CON_TC_SNO60>
J 2
(-375 2425);
PAINT ORANGE (-375 2425);
FORCEPROP 2 LAST CUSTOM_TXT_CDS <CON_TC_SNO59>
J 2
(-375 2525);
PAINT ORANGE (-375 2525);
FORCEPROP 2 LAST CUSTOM_TXT_CDS <CON_TC_SNO58>
J 2
(-375 2625);
PAINT ORANGE (-375 2625);
FORCEPROP 2 LAST CUSTOM_TXT_CDS <CON_TC_SNO57>
J 2
(-375 2725);
PAINT ORANGE (-375 2725);
FORCEPROP 2 LAST CUSTOM_TXT_CDS <CON_TC_SNO56>
J 2
(-375 2825);
PAINT ORANGE (-375 2825);
FORCEPROP 2 LAST CUSTOM_TXT_CDS <CON_TC_SNO55>
J 2
(-375 2925);
PAINT ORANGE (-375 2925);
FORCEPROP 2 LAST CUSTOM_TXT_CDS <CON_TC_SNO54>
J 2
(-375 3025);
PAINT ORANGE (-375 3025);
FORCEPROP 2 LAST CUSTOM_TXT_CDS <CON_TC_SNO53>
J 2
(-375 3125);
PAINT ORANGE (-375 3125);
FORCEPROP 2 LAST CUSTOM_TXT_CDS <CON_TC_SNO52>
J 2
(-375 3225);
PAINT ORANGE (-375 3225);
FORCEPROP 2 LAST CUSTOM_TXT_CDS <CON_TC_SNO51>
J 2
(-375 3325);
PAINT ORANGE (-375 3325);
FORCEPROP 2 LAST CUSTOM_TXT_CDS <CON_TC_SNO43>
J 2
(-375 4125);
PAINT ORANGE (-375 4125);
FORCEPROP 2 LAST CUSTOM_TXT_CDS <CON_TC_SNO42>
J 2
(-375 4225);
PAINT ORANGE (-375 4225);
FORCEPROP 2 LAST CUSTOM_TXT_CDS <CON_TC_SNO41>
J 2
(-375 4325);
PAINT ORANGE (-375 4325);
FORCEPROP 2 LAST CUSTOM_TXT_CDS <CON_TC_SNO40>
J 2
(-2875 425);
PAINT ORANGE (-2875 425);
FORCEPROP 2 LAST CUSTOM_TXT_CDS <CON_TC_SNO39>
J 2
(-2875 525);
PAINT ORANGE (-2875 525);
FORCEPROP 2 LAST CUSTOM_TXT_CDS <CON_TC_SNO36>
J 2
(-2875 825);
PAINT ORANGE (-2875 825);
FORCEPROP 2 LAST CUSTOM_TXT_CDS <CON_TC_SNO35>
J 2
(-2875 925);
PAINT ORANGE (-2875 925);
FORCEPROP 2 LAST CUSTOM_TXT_CDS <CON_TC_SNO34>
J 2
(-2875 1025);
PAINT ORANGE (-2875 1025);
FORCEPROP 2 LAST CUSTOM_TXT_CDS <CON_TC_SNO33>
J 2
(-2875 1125);
PAINT ORANGE (-2875 1125);
FORCEPROP 2 LAST CUSTOM_TXT_CDS <CON_TC_SNO32>
J 2
(-2875 1225);
PAINT ORANGE (-2875 1225);
FORCEPROP 2 LAST CUSTOM_TXT_CDS <CON_TC_SNO31>
J 2
(-2875 1325);
PAINT ORANGE (-2875 1325);
FORCEPROP 2 LAST CUSTOM_TXT_CDS <CON_TC_SNO30>
J 2
(-2875 1425);
PAINT ORANGE (-2875 1425);
FORCEPROP 2 LAST CUSTOM_TXT_CDS <CON_TC_SNO29>
J 2
(-2875 1525);
PAINT ORANGE (-2875 1525);
FORCEPROP 2 LAST CUSTOM_TXT_CDS <CON_TC_SNO28>
J 2
(-2875 1625);
PAINT ORANGE (-2875 1625);
FORCEPROP 2 LAST CUSTOM_TXT_CDS <CON_TC_SNO27>
J 2
(-2875 1725);
PAINT ORANGE (-2875 1725);
FORCEPROP 2 LAST CUSTOM_TXT_CDS <CON_TC_SNO26>
J 2
(-2875 1825);
PAINT ORANGE (-2875 1825);
FORCEPROP 2 LAST CUSTOM_TXT_CDS <CON_TC_SNO25>
J 2
(-2875 1925);
PAINT ORANGE (-2875 1925);
FORCEPROP 2 LAST CUSTOM_TXT_CDS <CON_TC_SNO24>
J 2
(-2875 2025);
PAINT ORANGE (-2875 2025);
FORCEPROP 2 LAST CUSTOM_TXT_CDS <CON_TC_SNO23>
J 2
(-2875 2125);
PAINT ORANGE (-2875 2125);
FORCEPROP 2 LAST CUSTOM_TXT_CDS <CON_TC_SNO22>
J 2
(-2875 2225);
PAINT ORANGE (-2875 2225);
FORCEPROP 2 LAST CUSTOM_TXT_CDS <CON_TC_SNO21>
J 2
(-2875 2325);
PAINT ORANGE (-2875 2325);
FORCEPROP 2 LAST CUSTOM_TXT_CDS <CON_TC_SNO20>
J 2
(-2875 2425);
PAINT ORANGE (-2875 2425);
FORCEPROP 2 LAST CUSTOM_TXT_CDS <CON_TC_SNO18>
J 2
(-2875 2625);
PAINT ORANGE (-2875 2625);
FORCEPROP 2 LAST CUSTOM_TXT_CDS <CON_TC_SNO17>
J 2
(-2875 2725);
PAINT ORANGE (-2875 2725);
FORCEPROP 2 LAST CUSTOM_TXT_CDS <CON_TC_SNO16>
J 2
(-2875 2825);
PAINT ORANGE (-2875 2825);
FORCEPROP 2 LAST CUSTOM_TXT_CDS <CON_TC_SNO15>
J 2
(-2875 2925);
PAINT ORANGE (-2875 2925);
FORCEPROP 2 LAST CUSTOM_TXT_CDS <CON_TC_SNO14>
J 2
(-2875 3025);
PAINT ORANGE (-2875 3025);
FORCEPROP 2 LAST CUSTOM_TXT_CDS <CON_TC_SNO13>
J 2
(-2875 3125);
PAINT ORANGE (-2875 3125);
FORCEPROP 2 LAST CUSTOM_TXT_CDS <CON_TC_SNO12>
J 2
(-2875 3225);
PAINT ORANGE (-2875 3225);
FORCEPROP 2 LAST CUSTOM_TXT_CDS <CON_TC_SNO11>
J 2
(-2875 3325);
PAINT ORANGE (-2875 3325);
FORCEPROP 2 LAST CUSTOM_TXT_CDS <CON_TC_SNO10>
J 2
(-2875 3425);
PAINT ORANGE (-2875 3425);
FORCEPROP 2 LAST CUSTOM_TXT_CDS <CON_TC_SNO9>
J 2
(-2875 3525);
PAINT ORANGE (-2875 3525);
FORCEPROP 2 LAST CUSTOM_TXT_CDS <CON_TC_SNO8>
J 2
(-2875 3625);
PAINT ORANGE (-2875 3625);
FORCEPROP 2 LAST CUSTOM_TXT_CDS <CON_TC_SNO5>
J 2
(-2875 3925);
PAINT ORANGE (-2875 3925);
FORCEPROP 2 LAST CUSTOM_TXT_CDS <CON_TC_SNM120>
J 0
(2225 425);
PAINT ORANGE (2225 425);
FORCEPROP 2 LAST CUSTOM_TXT_CDS <CON_TC_SNM119>
J 0
(2225 525);
PAINT ORANGE (2225 525);
FORCEPROP 2 LAST CUSTOM_TXT_CDS <CON_TC_SNM118>
J 0
(2225 625);
PAINT ORANGE (2225 625);
FORCEPROP 2 LAST CUSTOM_TXT_CDS <CON_TC_SNM117>
J 0
(2225 725);
PAINT ORANGE (2225 725);
FORCEPROP 2 LAST CUSTOM_TXT_CDS <CON_TC_SNM114>
J 0
(2225 1025);
PAINT ORANGE (2225 1025);
FORCEPROP 2 LAST CUSTOM_TXT_CDS <CON_TC_SNM103>
J 0
(2225 2125);
PAINT ORANGE (2225 2125);
FORCEPROP 2 LAST CUSTOM_TXT_CDS <CON_TC_SNM102>
J 0
(2225 2225);
PAINT ORANGE (2225 2225);
FORCEPROP 2 LAST CUSTOM_TXT_CDS <CON_TC_SNM101>
J 0
(2225 2325);
PAINT ORANGE (2225 2325);
FORCEPROP 2 LAST CUSTOM_TXT_CDS <CON_TC_SNM100>
J 0
(2225 2425);
PAINT ORANGE (2225 2425);
FORCEPROP 2 LAST CUSTOM_TXT_CDS <CON_TC_SNM99>
J 0
(2225 2525);
PAINT ORANGE (2225 2525);
FORCEPROP 2 LAST CUSTOM_TXT_CDS <CON_TC_SNM98>
J 0
(2225 2625);
PAINT ORANGE (2225 2625);
FORCEPROP 2 LAST CUSTOM_TXT_CDS <CON_TC_SNM97>
J 0
(2225 2725);
PAINT ORANGE (2225 2725);
FORCEPROP 2 LAST CUSTOM_TXT_CDS <CON_TC_SNM96>
J 0
(2225 2825);
PAINT ORANGE (2225 2825);
FORCEPROP 2 LAST CUSTOM_TXT_CDS <CON_TC_SNM95>
J 0
(2225 2925);
PAINT ORANGE (2225 2925);
FORCEPROP 2 LAST CUSTOM_TXT_CDS <CON_TC_SNM94>
J 0
(2225 3025);
PAINT ORANGE (2225 3025);
FORCEPROP 2 LAST CUSTOM_TXT_CDS <CON_TC_SNM93>
J 0
(2225 3125);
PAINT ORANGE (2225 3125);
FORCEPROP 2 LAST CUSTOM_TXT_CDS <CON_TC_SNM91>
J 0
(2225 3325);
PAINT ORANGE (2225 3325);
FORCEPROP 2 LAST CUSTOM_TXT_CDS <CON_TC_SNM90>
J 0
(2225 3425);
PAINT ORANGE (2225 3425);
FORCEPROP 2 LAST CUSTOM_TXT_CDS <CON_TC_SNM89>
J 0
(2225 3525);
PAINT ORANGE (2225 3525);
FORCEPROP 2 LAST CUSTOM_TXT_CDS <CON_TC_SNM88>
J 0
(2225 3625);
PAINT ORANGE (2225 3625);
FORCEPROP 2 LAST CUSTOM_TXT_CDS <CON_TC_SNM87>
J 0
(2225 3725);
PAINT ORANGE (2225 3725);
FORCEPROP 2 LAST CUSTOM_TXT_CDS <CON_TC_SNM86>
J 0
(2225 3825);
PAINT ORANGE (2225 3825);
FORCEPROP 2 LAST CUSTOM_TXT_CDS <CON_TC_SNM85>
J 0
(2225 3925);
PAINT ORANGE (2225 3925);
FORCEPROP 2 LAST CUSTOM_TXT_CDS <CON_TC_SNM84>
J 0
(2225 4025);
PAINT ORANGE (2225 4025);
FORCEPROP 2 LAST CUSTOM_TXT_CDS <CON_TC_SNM83>
J 0
(2225 4125);
PAINT ORANGE (2225 4125);
FORCEPROP 2 LAST CUSTOM_TXT_CDS <CON_TC_SNM82>
J 0
(2225 4225);
PAINT ORANGE (2225 4225);
FORCEPROP 2 LAST CUSTOM_TXT_CDS <CON_TC_SNM81>
J 0
(2225 4325);
PAINT ORANGE (2225 4325);
FORCEPROP 2 LAST CUSTOM_TXT_CDS <CON_TC_SNM78>
J 0
(-275 625);
PAINT ORANGE (-275 625);
FORCEPROP 2 LAST CUSTOM_TXT_CDS <CON_TC_SNM74>
J 0
(-275 1025);
PAINT ORANGE (-275 1025);
FORCEPROP 2 LAST CUSTOM_TXT_CDS <CON_TC_SNM73>
J 0
(-275 1125);
PAINT ORANGE (-275 1125);
FORCEPROP 2 LAST CUSTOM_TXT_CDS <CON_TC_SNM72>
J 0
(-275 1225);
PAINT ORANGE (-275 1225);
FORCEPROP 2 LAST CUSTOM_TXT_CDS <CON_TC_SNM71>
J 0
(-275 1325);
PAINT ORANGE (-275 1325);
FORCEPROP 2 LAST CUSTOM_TXT_CDS <CON_TC_SNM70>
J 0
(-275 1425);
PAINT ORANGE (-275 1425);
FORCEPROP 2 LAST CUSTOM_TXT_CDS <CON_TC_SNM69>
J 0
(-275 1525);
PAINT ORANGE (-275 1525);
FORCEPROP 2 LAST CUSTOM_TXT_CDS <CON_TC_SNM68>
J 0
(-275 1625);
PAINT ORANGE (-275 1625);
FORCEPROP 2 LAST CUSTOM_TXT_CDS <CON_TC_SNM67>
J 0
(-275 1725);
PAINT ORANGE (-275 1725);
FORCEPROP 2 LAST CUSTOM_TXT_CDS <CON_TC_SNM66>
J 0
(-275 1825);
PAINT ORANGE (-275 1825);
FORCEPROP 2 LAST CUSTOM_TXT_CDS <CON_TC_SNM65>
J 0
(-275 1925);
PAINT ORANGE (-275 1925);
FORCEPROP 2 LAST CUSTOM_TXT_CDS <CON_TC_SNM64>
J 0
(-275 2025);
PAINT ORANGE (-275 2025);
FORCEPROP 2 LAST CUSTOM_TXT_CDS <CON_TC_SNM62>
J 0
(-275 2225);
PAINT ORANGE (-275 2225);
FORCEPROP 2 LAST CUSTOM_TXT_CDS <CON_TC_SNM60>
J 0
(-275 2425);
PAINT ORANGE (-275 2425);
FORCEPROP 2 LAST CUSTOM_TXT_CDS <CON_TC_SNM59>
J 0
(-275 2525);
PAINT ORANGE (-275 2525);
FORCEPROP 2 LAST CUSTOM_TXT_CDS <CON_TC_SNM58>
J 0
(-275 2625);
PAINT ORANGE (-275 2625);
FORCEPROP 2 LAST CUSTOM_TXT_CDS <CON_TC_SNM57>
J 0
(-275 2725);
PAINT ORANGE (-275 2725);
FORCEPROP 2 LAST CUSTOM_TXT_CDS <CON_TC_SNM51>
J 0
(-275 3325);
PAINT ORANGE (-275 3325);
FORCEPROP 2 LAST CUSTOM_TXT_CDS <CON_TC_SNM47>
J 0
(-275 3725);
PAINT ORANGE (-275 3725);
FORCEPROP 2 LAST CUSTOM_TXT_CDS <CON_TC_SNM46>
J 0
(-275 3825);
PAINT ORANGE (-275 3825);
FORCEPROP 2 LAST CUSTOM_TXT_CDS <CON_TC_SNM45>
J 0
(-275 3925);
PAINT ORANGE (-275 3925);
FORCEPROP 2 LAST CUSTOM_TXT_CDS <CON_TC_SNM40>
J 0
(-2775 425);
PAINT ORANGE (-2775 425);
FORCEPROP 2 LAST CUSTOM_TXT_CDS <CON_TC_SNM39>
J 0
(-2775 525);
PAINT ORANGE (-2775 525);
FORCEPROP 2 LAST CUSTOM_TXT_CDS <CON_TC_SNM38>
J 0
(-2775 625);
PAINT ORANGE (-2775 625);
FORCEPROP 2 LAST CUSTOM_TXT_CDS <CON_TC_SNM37>
J 0
(-2775 725);
PAINT ORANGE (-2775 725);
FORCEPROP 2 LAST CUSTOM_TXT_CDS <CON_TC_SNM36>
J 0
(-2775 825);
PAINT ORANGE (-2775 825);
FORCEPROP 2 LAST CUSTOM_TXT_CDS <CON_TC_SNM34>
J 0
(-2775 1025);
PAINT ORANGE (-2775 1025);
FORCEPROP 2 LAST CUSTOM_TXT_CDS <CON_TC_SNM33>
J 0
(-2775 1125);
PAINT ORANGE (-2775 1125);
FORCEPROP 2 LAST CUSTOM_TXT_CDS <CON_TC_SNM31>
J 0
(-2775 1325);
PAINT ORANGE (-2775 1325);
FORCEPROP 2 LAST CUSTOM_TXT_CDS <CON_TC_SNM30>
J 0
(-2775 1425);
PAINT ORANGE (-2775 1425);
FORCEPROP 2 LAST CUSTOM_TXT_CDS <CON_TC_SNM29>
J 0
(-2775 1525);
PAINT ORANGE (-2775 1525);
FORCEPROP 2 LAST CUSTOM_TXT_CDS <CON_TC_SNM28>
J 0
(-2775 1625);
PAINT ORANGE (-2775 1625);
FORCEPROP 2 LAST CUSTOM_TXT_CDS <CON_TC_SNM26>
J 0
(-2775 1825);
PAINT ORANGE (-2775 1825);
FORCEPROP 2 LAST CUSTOM_TXT_CDS <CON_TC_SNM25>
J 0
(-2775 1925);
PAINT ORANGE (-2775 1925);
FORCEPROP 2 LAST CUSTOM_TXT_CDS <CON_TC_SNM24>
J 0
(-2775 2025);
PAINT ORANGE (-2775 2025);
FORCEPROP 2 LAST CUSTOM_TXT_CDS <CON_TC_SNM23>
J 0
(-2775 2125);
PAINT ORANGE (-2775 2125);
FORCEPROP 2 LAST CUSTOM_TXT_CDS <CON_TC_SNM22>
J 0
(-2775 2225);
PAINT ORANGE (-2775 2225);
FORCEPROP 2 LAST CUSTOM_TXT_CDS <CON_TC_SNM20>
J 0
(-2775 2425);
PAINT ORANGE (-2775 2425);
FORCEPROP 2 LAST CUSTOM_TXT_CDS <CON_TC_SNM18>
J 0
(-2775 2625);
PAINT ORANGE (-2775 2625);
FORCEPROP 2 LAST CUSTOM_TXT_CDS <CON_TC_SNM16>
J 0
(-2775 2825);
PAINT ORANGE (-2775 2825);
FORCEPROP 2 LAST CUSTOM_TXT_CDS <CON_TC_SNM14>
J 0
(-2775 3025);
PAINT ORANGE (-2775 3025);
FORCEPROP 2 LAST CUSTOM_TXT_CDS <CON_TC_SNM13>
J 0
(-2775 3125);
PAINT ORANGE (-2775 3125);
FORCEPROP 2 LAST CUSTOM_TXT_CDS <CON_TC_SNM12>
J 0
(-2775 3225);
PAINT ORANGE (-2775 3225);
FORCEPROP 2 LAST CUSTOM_TXT_CDS <CON_TC_SNM9>
J 0
(-2775 3525);
PAINT ORANGE (-2775 3525);
FORCEPROP 2 LAST CUSTOM_TXT_CDS <CON_TC_SNM7>
J 0
(-2775 3725);
PAINT ORANGE (-2775 3725);
FORCEPROP 1 LAST SCH_TITLE INDEX (2 OF 3)
J 0
(-3675 -150);
DISPLAY 1.212766 (-3675 -150);
PAINT ORANGE (-3675 -150);
FORCEPROP 1 LAST COMMENT_BODY TRUE
J 0
(4287 -188);
DISPLAY 0.468085 (4287 -188);
PAINT GREEN (4287 -188);
DISPLAY INVISIBLE (4287 -188);
FORCEPROP 1 LAST TOC_SYMBOL TRUE
J 0
(-3675 4850);
PAINT ORANGE (-3675 4850);
DISPLAY INVISIBLE (-3675 4850);
FORCEPROP 2 LAST CDS_LIB mstr_symbols
J 0
(4275 -200);
PAINT MONO (4275 -200);
DISPLAY INVISIBLE (4275 -200);
FORCEPROP 2 LAST PAGE_BORDER TRUE
J 0
(-3615 5050);
DISPLAY 0.638298 (-3615 5050);
PAINT PINK (-3615 5050);
DISPLAY INVISIBLE (-3615 5050);
FORCEPROP 2 LAST CDS_XR_PAGE_TITLE CR-3 : @BASEBOARD_FAB2_LIB.BASEBOARD_FAB2(SCH_1):PAGE3
J 0
(-3615 5050);
DISPLAY 0.638298 (-3615 5050);
PAINT PINK (-3615 5050);
DISPLAY INVISIBLE (-3615 5050);
QUIT
